G04*
G04 #@! TF.GenerationSoftware,Altium Limited,Altium Designer,23.6.0 (18)*
G04*
G04 Layer_Color=16711935*
%FSLAX44Y44*%
%MOMM*%
G71*
G04*
G04 #@! TF.SameCoordinates,59133E90-4310-4D8A-9E2C-91A8D2F69FBB*
G04*
G04*
G04 #@! TF.FilePolarity,Negative*
G04*
G01*
G75*
%ADD49C,0.5064*%
%ADD62R,0.4500X2.0500*%
%ADD63C,6.1000*%
D49*
X211156Y38620D02*
D03*
X126000Y100000D02*
D03*
X104000Y107000D02*
D03*
X209830Y407680D02*
D03*
Y397520D02*
D03*
Y387360D02*
D03*
Y377200D02*
D03*
Y367040D02*
D03*
Y356880D02*
D03*
Y346720D02*
D03*
Y336560D02*
D03*
Y326400D02*
D03*
X199670Y407680D02*
D03*
Y397520D02*
D03*
Y387360D02*
D03*
Y377200D02*
D03*
Y367040D02*
D03*
Y356880D02*
D03*
Y346720D02*
D03*
Y336560D02*
D03*
Y326400D02*
D03*
X189510Y387360D02*
D03*
Y367040D02*
D03*
Y356880D02*
D03*
Y346720D02*
D03*
Y336560D02*
D03*
Y326400D02*
D03*
X179350Y367040D02*
D03*
Y356880D02*
D03*
Y346720D02*
D03*
Y336560D02*
D03*
X169190Y407680D02*
D03*
X159030Y387360D02*
D03*
Y377200D02*
D03*
Y356880D02*
D03*
Y346720D02*
D03*
Y336560D02*
D03*
X148870Y387360D02*
D03*
Y346720D02*
D03*
X138710Y397520D02*
D03*
Y387360D02*
D03*
X128550D02*
D03*
X118390D02*
D03*
X98070D02*
D03*
X87910Y306080D02*
D03*
X77750Y407680D02*
D03*
Y387360D02*
D03*
Y356880D02*
D03*
X67590Y397520D02*
D03*
Y306080D02*
D03*
Y295920D02*
D03*
Y285760D02*
D03*
Y275600D02*
D03*
X190545Y43935D02*
D03*
X115000Y146000D02*
D03*
X106178Y147000D02*
D03*
X115000Y139000D02*
D03*
X168000Y131000D02*
D03*
X204000Y111000D02*
D03*
X166000Y112000D02*
D03*
X201000Y120000D02*
D03*
X167000D02*
D03*
X154373Y105997D02*
D03*
X210000Y181100D02*
D03*
Y192100D02*
D03*
X76611Y127172D02*
D03*
X52102Y139442D02*
D03*
X53051Y126729D02*
D03*
X41792Y117242D02*
D03*
X39452Y130651D02*
D03*
X12000Y65000D02*
D03*
Y74000D02*
D03*
X37758Y73000D02*
D03*
X37000Y64000D02*
D03*
X206000Y52000D02*
D03*
X197000D02*
D03*
X207000Y77000D02*
D03*
X198000D02*
D03*
X204000Y40054D02*
D03*
X191000Y37000D02*
D03*
X90162Y85574D02*
D03*
X80512Y67616D02*
D03*
X106948Y62472D02*
D03*
X93057Y101595D02*
D03*
X94793Y112219D02*
D03*
X65988Y100369D02*
D03*
X66000Y112000D02*
D03*
X145027Y145180D02*
D03*
X128214Y138000D02*
D03*
X181826Y161442D02*
D03*
X148849Y161221D02*
D03*
X138262Y162104D02*
D03*
X83228D02*
D03*
X83000Y146000D02*
D03*
X91831Y146884D02*
D03*
X37000Y194600D02*
D03*
X58000D02*
D03*
X79000D02*
D03*
X100000Y194000D02*
D03*
X121000Y194600D02*
D03*
X142000D02*
D03*
X163000D02*
D03*
X184000Y194600D02*
D03*
X37000Y215600D02*
D03*
X58000D02*
D03*
X79000D02*
D03*
X100000Y215000D02*
D03*
X121000Y215600D02*
D03*
X142000D02*
D03*
X163000D02*
D03*
X184000Y215600D02*
D03*
X37000Y236600D02*
D03*
X58000D02*
D03*
X79000D02*
D03*
X100000Y236000D02*
D03*
X121000Y236600D02*
D03*
X142000D02*
D03*
X163000D02*
D03*
X184000Y236600D02*
D03*
X37000Y257000D02*
D03*
X58000D02*
D03*
X79000D02*
D03*
X100000Y256400D02*
D03*
X121000Y257000D02*
D03*
X142000D02*
D03*
X163000D02*
D03*
X184000Y257000D02*
D03*
X37000Y278600D02*
D03*
X58000D02*
D03*
X79000D02*
D03*
X100000Y278000D02*
D03*
X121000Y278600D02*
D03*
X142000D02*
D03*
X163000D02*
D03*
X184000Y278600D02*
D03*
Y299600D02*
D03*
X163000Y299600D02*
D03*
X142000D02*
D03*
X121000D02*
D03*
X100000Y299000D02*
D03*
X79000Y299600D02*
D03*
X58000D02*
D03*
X37000D02*
D03*
X210000Y203100D02*
D03*
Y214100D02*
D03*
Y236100D02*
D03*
Y258100D02*
D03*
Y302100D02*
D03*
Y313100D02*
D03*
X149024Y334175D02*
D03*
X137823Y333314D02*
D03*
X126909Y334032D02*
D03*
X17430Y401507D02*
D03*
X68713Y403287D02*
D03*
X14291Y409878D02*
D03*
X11151Y401828D02*
D03*
X53974Y359649D02*
D03*
X23386Y401023D02*
D03*
X51000Y371000D02*
D03*
X50396Y377474D02*
D03*
X31414Y403184D02*
D03*
X11000Y339000D02*
D03*
X18519Y343994D02*
D03*
X26000Y349000D02*
D03*
X11000D02*
D03*
X49915Y341352D02*
D03*
X39824Y361855D02*
D03*
X63000Y38000D02*
D03*
X176000Y44000D02*
D03*
X111000Y35000D02*
D03*
X152000Y36000D02*
D03*
X137000D02*
D03*
X123000Y35000D02*
D03*
X93000Y34000D02*
D03*
X33000Y31000D02*
D03*
Y38000D02*
D03*
X32880Y45166D02*
D03*
X33000Y51645D02*
D03*
X15000Y50312D02*
D03*
X12791Y42000D02*
D03*
X6395Y41971D02*
D03*
X6826Y50312D02*
D03*
D62*
X140060Y15250D02*
D03*
X135060D02*
D03*
X130060D02*
D03*
X125060D02*
D03*
X120060D02*
D03*
X115060D02*
D03*
X110060D02*
D03*
X155060D02*
D03*
X150060D02*
D03*
X80060D02*
D03*
X90060D02*
D03*
X85060D02*
D03*
X95060D02*
D03*
X75060D02*
D03*
X70060D02*
D03*
X65060D02*
D03*
X60060D02*
D03*
X55060D02*
D03*
X50060D02*
D03*
X45060D02*
D03*
X40060D02*
D03*
X35060D02*
D03*
X30060D02*
D03*
X25060D02*
D03*
X100060D02*
D03*
X105060D02*
D03*
X145060D02*
D03*
X185060D02*
D03*
X200060D02*
D03*
X195060D02*
D03*
X190060D02*
D03*
X180060D02*
D03*
X20060D02*
D03*
D63*
X110000Y420000D02*
D03*
M02*
